# BASEBOARD_FAB2 (Tioga Pass) — schematic netlist excerpt (pin names and nets, part order shuffled) for the footprints in the layout excerpt that follows; sources: Cadence DE-HDL packaged netlist, KiCad conversion of Wiwynn_Tioga_Pass_MB.brd

R4B9  RES  1.0K 0.1% CHIP  pkg 0402  page 234 : A = VSENSE_PVPP_KLM ; B = VR_COMP_PVPP_KLM
C8C14  CAP_A  0.1UF 16V 10% X7R  pkg 0402V  page 188 : A = KR_P0_OCP_RX_DN ; B = KR_P0_OCP_RX_C_DN
R4D6  RES  27.4 1% CHIP  pkg 0402  page 103 : A = CLK_100M_CPU0_RC_REFCLK1_R_DP ; B = CLK_100M_CPU0_RC_REFCLK1_DP

(kicad_pcb
	(version 20260206)
	(generator "pcbnew")
	(generator_version "10.0")
	(general
		(thickness 1.6)
		(legacy_teardrops no)
	)
	(paper "A4")
	(title_block
		(title "Wiwynn_Tioga_Pass_MB.brd")
		(comment 1 "Tioga Pass / footprints 1407-1409 of 4770")
	)
	(layers
		(0 "F.Cu" signal "TOP")
		(4 "In1.Cu" signal "L2GND")
		(6 "In2.Cu" signal "L3")
		(8 "In3.Cu" signal "L4GND")
		(10 "In4.Cu" signal "L5")
		(12 "In5.Cu" signal "L6GND")
		(14 "In6.Cu" signal "L7VCC")
		(16 "In7.Cu" signal "L8VCC")
		(18 "In8.Cu" signal "L9GND")
		(20 "In9.Cu" signal "L10")
		(22 "In10.Cu" signal "L11GND")
		(24 "In11.Cu" signal "L12")
		(26 "In12.Cu" signal "L13GND")
		(2 "B.Cu" signal "BOTTOM")
		(9 "F.Adhes" user "F.Adhesive")
		(11 "B.Adhes" user "B.Adhesive")
		(13 "F.Paste" user "Package Geometry/Pastemask Top")
		(15 "B.Paste" user "Package Geometry/Pastemask Bottom")
		(5 "F.SilkS" user "Ref Des/Silkscreen Top")
		(7 "B.SilkS" user "Ref Des/Silkscreen Bottom")
		(1 "F.Mask" user "Board Geometry/Soldermask Top")
		(3 "B.Mask" user "Board Geometry/Soldermask Bottom")
		(17 "Dwgs.User" user "User.Drawings")
		(19 "Cmts.User" user "User.Comments")
		(21 "Eco1.User" user "User.Eco1")
		(23 "Eco2.User" user "User.Eco2")
		(25 "Edge.Cuts" user "Board Geometry/Outline")
		(27 "Margin" user)
		(31 "F.CrtYd" user "Package Geometry/Place Bound Top")
		(29 "B.CrtYd" user "Package Geometry/Place Bound Bottom")
		(35 "F.Fab" user "Ref Des/Assembly Top")
		(33 "B.Fab" user "Ref Des/Assembly Bottom")
	)
	(footprint ""
		(layer "F.Cu")
		(at 171.196 -86.868 180)
		(property "Reference" "R4D6"
			(at 0 0 180)
			(layer "F.SilkS")
			(hide yes)
			(effects
				(font
					(size 1.27 1.27)
				)
			)
		)
		(property "Value" ""
			(at 0 0 180)
			(layer "F.Fab")
			(effects
				(font
					(size 1.27 1.27)
				)
			)
		)
		(duplicate_pad_numbers_are_jumpers no)
		(fp_poly
			(pts
				(xy -0.2794 -0.1016) (xy 0.2794 -0.1016) (xy 0.2794 0.9906) (xy -0.2794 0.9906)
			)
			(stroke
				(width 0)
				(type default)
			)
			(fill no)
			(layer "F.CrtYd")
		)
		(fp_line
			(start 0.2794 0.9906)
			(end 0.2794 -0.1016)
			(stroke
				(width 0.1)
				(type default)
			)
			(layer "F.Fab")
		)
		(fp_line
			(start 0.2794 -0.1016)
			(end -0.2794 -0.1016)
			(stroke
				(width 0.1)
				(type default)
			)
			(layer "F.Fab")
		)
		(fp_line
			(start -0.2794 0.9906)
			(end 0.2794 0.9906)
			(stroke
				(width 0.1)
				(type default)
			)
			(layer "F.Fab")
		)
		(fp_line
			(start -0.2794 -0.1016)
			(end -0.2794 0.9906)
			(stroke
				(width 0.1)
				(type default)
			)
			(layer "F.Fab")
		)
		(pad "1" smd rect
			(at 0 0 180)
			(size 0.508 0.508)
			(layers "F.Cu" "F.Mask" "F.Paste")
			(net "CLK_100M_CPU0_RC_REFCLK1_R_DP")
		)
		(pad "2" smd rect
			(at 0 0.889 180)
			(size 0.508 0.508)
			(layers "F.Cu" "F.Mask" "F.Paste")
			(net "CLK_100M_CPU0_RC_REFCLK1_DP")
		)
		(zone
			(layer "F.Cu")
			(hatch none 0.5)
			(connect_pads
				(clearance 0)
			)
			(min_thickness 0.25)
			(keepout
				(tracks not_allowed)
				(vias allowed)
				(pads allowed)
				(copperpour not_allowed)
				(footprints allowed)
			)
			(placement
				(enabled no)
				(sheetname "")
			)
			(fill
				(thermal_gap 0.5)
				(thermal_bridge_width 0.5)
				(island_removal_mode 0)
			)
			(polygon
				(pts
					(xy 171.45 -87.503) (xy 170.942 -87.503) (xy 170.942 -87.122) (xy 171.45 -87.122)
				)
			)
		)
		(zone
			(layer "F.Cu")
			(hatch none 0.5)
			(connect_pads
				(clearance 0)
			)
			(min_thickness 0.25)
			(keepout
				(tracks allowed)
				(vias not_allowed)
				(pads allowed)
				(copperpour not_allowed)
				(footprints allowed)
			)
			(placement
				(enabled no)
				(sheetname "")
			)
			(fill
				(thermal_gap 0.5)
				(thermal_bridge_width 0.5)
				(island_removal_mode 0)
			)
			(polygon
				(pts
					(xy 171.45 -87.122) (xy 170.942 -87.122) (xy 170.942 -87.503) (xy 171.45 -87.503)
				)
			)
		)
	)
	(footprint ""
		(layer "F.Cu")
		(at 418.7952 -92.6719 -90)
		(property "Reference" "C8C14"
			(at 0 0 270)
			(layer "F.SilkS")
			(hide yes)
			(effects
				(font
					(size 1.27 1.27)
				)
			)
		)
		(property "Value" ""
			(at 0 0 270)
			(layer "F.Fab")
			(effects
				(font
					(size 1.27 1.27)
				)
			)
		)
		(duplicate_pad_numbers_are_jumpers no)
		(fp_poly
			(pts
				(xy 0.3048 -0.1016) (xy 0.3048 0.9906) (xy -0.3048 0.9906) (xy -0.3048 -0.1016)
			)
			(stroke
				(width 0)
				(type default)
			)
			(fill no)
			(layer "F.CrtYd")
		)
		(fp_line
			(start -0.3048 0.9906)
			(end 0.3048 0.9906)
			(stroke
				(width 0.1)
				(type default)
			)
			(layer "F.Fab")
		)
		(fp_line
			(start 0.3048 0.9906)
			(end 0.3048 -0.1016)
			(stroke
				(width 0.1)
				(type default)
			)
			(layer "F.Fab")
		)
		(fp_line
			(start -0.3048 -0.1016)
			(end -0.3048 0.9906)
			(stroke
				(width 0.1)
				(type default)
			)
			(layer "F.Fab")
		)
		(fp_line
			(start 0.3048 -0.1016)
			(end -0.3048 -0.1016)
			(stroke
				(width 0.1)
				(type default)
			)
			(layer "F.Fab")
		)
		(pad "1" smd rect
			(at 0 0 270)
			(size 0.508 0.508)
			(layers "F.Cu" "F.Mask" "F.Paste")
			(net "KR_P0_OCP_RX_DN")
		)
		(pad "2" smd rect
			(at 0 0.889 270)
			(size 0.508 0.508)
			(layers "F.Cu" "F.Mask" "F.Paste")
			(net "KR_P0_OCP_RX_C_DN")
		)
		(zone
			(layer "F.Cu")
			(hatch none 0.5)
			(connect_pads
				(clearance 0)
			)
			(min_thickness 0.25)
			(keepout
				(tracks not_allowed)
				(vias allowed)
				(pads allowed)
				(copperpour not_allowed)
				(footprints allowed)
			)
			(placement
				(enabled no)
				(sheetname "")
			)
			(fill
				(thermal_gap 0.5)
				(thermal_bridge_width 0.5)
				(island_removal_mode 0)
			)
			(polygon
				(pts
					(xy 418.1602 -92.9259) (xy 418.1602 -92.4179) (xy 418.5412 -92.4179) (xy 418.5412 -92.9259)
				)
			)
		)
		(zone
			(layer "F.Cu")
			(hatch none 0.5)
			(connect_pads
				(clearance 0)
			)
			(min_thickness 0.25)
			(keepout
				(tracks allowed)
				(vias not_allowed)
				(pads allowed)
				(copperpour not_allowed)
				(footprints allowed)
			)
			(placement
				(enabled no)
				(sheetname "")
			)
			(fill
				(thermal_gap 0.5)
				(thermal_bridge_width 0.5)
				(island_removal_mode 0)
			)
			(polygon
				(pts
					(xy 418.5412 -92.9259) (xy 418.5412 -92.4179) (xy 418.1602 -92.4179) (xy 418.1602 -92.9259)
				)
			)
		)
	)
	(footprint ""
		(layer "F.Cu")
		(at 170.6245 -130.175 90)
		(property "Reference" "R4B9"
			(at 0 0 90)
			(layer "F.SilkS")
			(hide yes)
			(effects
				(font
					(size 1.27 1.27)
				)
			)
		)
		(property "Value" ""
			(at 0 0 90)
			(layer "F.Fab")
			(effects
				(font
					(size 1.27 1.27)
				)
			)
		)
		(duplicate_pad_numbers_are_jumpers no)
		(fp_poly
			(pts
				(xy -0.2794 -0.1016) (xy 0.2794 -0.1016) (xy 0.2794 0.9906) (xy -0.2794 0.9906)
			)
			(stroke
				(width 0)
				(type default)
			)
			(fill no)
			(layer "F.CrtYd")
		)
		(fp_line
			(start 0.2794 -0.1016)
			(end -0.2794 -0.1016)
			(stroke
				(width 0.1)
				(type default)
			)
			(layer "F.Fab")
		)
		(fp_line
			(start -0.2794 -0.1016)
			(end -0.2794 0.9906)
			(stroke
				(width 0.1)
				(type default)
			)
			(layer "F.Fab")
		)
		(fp_line
			(start 0.2794 0.9906)
			(end 0.2794 -0.1016)
			(stroke
				(width 0.1)
				(type default)
			)
			(layer "F.Fab")
		)
		(fp_line
			(start -0.2794 0.9906)
			(end 0.2794 0.9906)
			(stroke
				(width 0.1)
				(type default)
			)
			(layer "F.Fab")
		)
		(pad "1" smd rect
			(at 0 0 90)
			(size 0.508 0.508)
			(layers "F.Cu" "F.Mask" "F.Paste")
			(net "VSENSE_PVPP_KLM")
		)
		(pad "2" smd rect
			(at 0 0.889 90)
			(size 0.508 0.508)
			(layers "F.Cu" "F.Mask" "F.Paste")
			(net "VR_COMP_PVPP_KLM")
		)
		(zone
			(layer "F.Cu")
			(hatch none 0.5)
			(connect_pads
				(clearance 0)
			)
			(min_thickness 0.25)
			(keepout
				(tracks allowed)
				(vias not_allowed)
				(pads allowed)
				(copperpour not_allowed)
				(footprints allowed)
			)
			(placement
				(enabled no)
				(sheetname "")
			)
			(fill
				(thermal_gap 0.5)
				(thermal_bridge_width 0.5)
				(island_removal_mode 0)
			)
			(polygon
				(pts
					(xy 170.8785 -129.921) (xy 170.8785 -130.429) (xy 171.2595 -130.429) (xy 171.2595 -129.921)
				)
			)
		)
		(zone
			(layer "F.Cu")
			(hatch none 0.5)
			(connect_pads
				(clearance 0)
			)
			(min_thickness 0.25)
			(keepout
				(tracks not_allowed)
				(vias allowed)
				(pads allowed)
				(copperpour not_allowed)
				(footprints allowed)
			)
			(placement
				(enabled no)
				(sheetname "")
			)
			(fill
				(thermal_gap 0.5)
				(thermal_bridge_width 0.5)
				(island_removal_mode 0)
			)
			(polygon
				(pts
					(xy 171.2595 -129.921) (xy 171.2595 -130.429) (xy 170.8785 -130.429) (xy 170.8785 -129.921)
				)
			)
		)
	)
)
